# S9S_MB_2U (Grand Teton) — schematic netlist excerpt (pin names and nets, part order shuffled) for the footprints in the layout excerpt that follows; sources: Cadence DE-HDL packaged netlist, KiCad conversion of 03242023_DA0F0TMBIJ0_F0T_Motherboard_J_brd_V01_OCP.brd

R1673  Q_RES  10K 1% CHIP  pkg 0402LF  page 191 : A = P3V3_E1S_0 ; B = RST_SMB_E1S_0_N
PC297_P0_1  Q_CAP  3300PF 50V 10% X7R  pkg 0402  page 267 : A = SW_P12V_PVCCIN_CPU0_FLT ; B = GND

(kicad_pcb
	(version 20260206)
	(generator "pcbnew")
	(generator_version "10.0")
	(general
		(thickness 1.6)
		(legacy_teardrops no)
	)
	(paper "A4")
	(title_block
		(title "03242023_DA0F0TMBIJ0_F0T_Motherboard_J_brd_V01_OCP.brd")
		(comment 1 "Grand Teton / footprints 1756-1757 of 6105")
	)
	(layers
		(0 "F.Cu" signal "TOP")
		(4 "In1.Cu" signal "GND")
		(6 "In2.Cu" signal "IN1")
		(8 "In3.Cu" signal "GND1")
		(10 "In4.Cu" signal "IN2")
		(12 "In5.Cu" signal "GND2")
		(14 "In6.Cu" signal "IN3")
		(16 "In7.Cu" signal "GND3")
		(18 "In8.Cu" signal "VCC")
		(20 "In9.Cu" signal "VCC1")
		(22 "In10.Cu" signal "GND4")
		(24 "In11.Cu" signal "IN4")
		(26 "In12.Cu" signal "GND5")
		(28 "In13.Cu" signal "IN5")
		(30 "In14.Cu" signal "GND6")
		(32 "In15.Cu" signal "IN6")
		(34 "In16.Cu" signal "GND7")
		(2 "B.Cu" signal "BOTTOM")
		(9 "F.Adhes" user "F.Adhesive")
		(11 "B.Adhes" user "B.Adhesive")
		(13 "F.Paste" user "Package Geometry/Pastemask Top")
		(15 "B.Paste" user "Package Geometry/Pastemask Bottom")
		(5 "F.SilkS" user "Ref Des/Silkscreen Top")
		(7 "B.SilkS" user "Ref Des/Silkscreen Bottom")
		(1 "F.Mask" user "Board Geometry/Soldermask Top")
		(3 "B.Mask" user "Board Geometry/Soldermask Bottom")
		(17 "Dwgs.User" user "User.Drawings")
		(19 "Cmts.User" user "User.Comments")
		(21 "Eco1.User" user "User.Eco1")
		(23 "Eco2.User" user "User.Eco2")
		(25 "Edge.Cuts" user "Board Geometry/Outline")
		(27 "Margin" user)
		(31 "F.CrtYd" user "Package Geometry/Place Bound Top")
		(29 "B.CrtYd" user "Package Geometry/Place Bound Bottom")
		(35 "F.Fab" user "Ref Des/Assembly Top")
		(33 "B.Fab" user "Ref Des/Assembly Bottom")
	)
	(footprint ""
		(layer "F.Cu")
		(at 348.929198 -337.856068)
		(property "Reference" "PC297_P0_1"
			(at 0 0 0)
			(layer "F.SilkS")
			(hide yes)
			(effects
				(font
					(size 1.27 1.27)
				)
			)
		)
		(property "Value" ""
			(at 0 0 0)
			(layer "F.Fab")
			(effects
				(font
					(size 1.27 1.27)
				)
			)
		)
		(duplicate_pad_numbers_are_jumpers no)
		(fp_line
			(start -0.7874 -0.4064)
			(end 0.7874 -0.4064)
			(stroke
				(width 0.1524)
				(type default)
			)
			(layer "F.SilkS")
		)
		(fp_line
			(start -0.7874 0.4064)
			(end -0.7874 -0.4064)
			(stroke
				(width 0.1524)
				(type default)
			)
			(layer "F.SilkS")
		)
		(fp_line
			(start 0.7874 -0.4064)
			(end 0.7874 0.4064)
			(stroke
				(width 0.1524)
				(type default)
			)
			(layer "F.SilkS")
		)
		(fp_line
			(start 0.7874 0.4064)
			(end -0.7874 0.4064)
			(stroke
				(width 0.1524)
				(type default)
			)
			(layer "F.SilkS")
		)
		(fp_line
			(start -0.67945 -0.305054)
			(end -0.12065 -0.305054)
			(stroke
				(width 0.1)
				(type default)
			)
			(layer "F.Fab")
		)
		(fp_line
			(start -0.67945 0.3048)
			(end -0.67945 -0.305054)
			(stroke
				(width 0.1)
				(type default)
			)
			(layer "F.Fab")
		)
		(fp_line
			(start -0.12065 -0.305054)
			(end -0.12065 -0.2794)
			(stroke
				(width 0.1)
				(type default)
			)
			(layer "F.Fab")
		)
		(fp_line
			(start -0.12065 -0.2794)
			(end 0.12065 -0.2794)
			(stroke
				(width 0.1)
				(type default)
			)
			(layer "F.Fab")
		)
		(fp_line
			(start -0.12065 0.2794)
			(end -0.12065 0.3048)
			(stroke
				(width 0.1)
				(type default)
			)
			(layer "F.Fab")
		)
		(fp_line
			(start -0.12065 0.3048)
			(end -0.67945 0.3048)
			(stroke
				(width 0.1)
				(type default)
			)
			(layer "F.Fab")
		)
		(fp_line
			(start 0.120396 0.2794)
			(end -0.12065 0.2794)
			(stroke
				(width 0.1)
				(type default)
			)
			(layer "F.Fab")
		)
		(fp_line
			(start 0.120396 0.3048)
			(end 0.120396 0.2794)
			(stroke
				(width 0.1)
				(type default)
			)
			(layer "F.Fab")
		)
		(fp_line
			(start 0.12065 -0.3048)
			(end 0.67945 -0.3048)
			(stroke
				(width 0.1)
				(type default)
			)
			(layer "F.Fab")
		)
		(fp_line
			(start 0.12065 -0.2794)
			(end 0.12065 -0.3048)
			(stroke
				(width 0.1)
				(type default)
			)
			(layer "F.Fab")
		)
		(fp_line
			(start 0.67945 -0.3048)
			(end 0.67945 0.3048)
			(stroke
				(width 0.1)
				(type default)
			)
			(layer "F.Fab")
		)
		(fp_line
			(start 0.67945 0.3048)
			(end 0.120396 0.3048)
			(stroke
				(width 0.1)
				(type default)
			)
			(layer "F.Fab")
		)
		(pad "1" smd circle
			(at -0.40005 0)
			(size 0 0)
			(layers "F.Cu" "F.Mask" "F.Paste")
			(net "SW_P12V_PVCCIN_CPU0_FLT")
		)
		(pad "2" smd circle
			(at 0.40005 0)
			(size 0 0)
			(layers "F.Cu" "F.Mask" "F.Paste")
			(net "GND")
		)
	)
	(footprint ""
		(layer "F.Cu")
		(at 224.20961 -46.524926)
		(property "Reference" "R1673"
			(at 0 0 0)
			(layer "F.SilkS")
			(hide yes)
			(effects
				(font
					(size 1.27 1.27)
				)
			)
		)
		(property "Value" ""
			(at 0 0 0)
			(layer "F.Fab")
			(effects
				(font
					(size 1.27 1.27)
				)
			)
		)
		(duplicate_pad_numbers_are_jumpers no)
		(fp_line
			(start -0.7874 -0.4064)
			(end 0.7874 -0.4064)
			(stroke
				(width 0.1524)
				(type default)
			)
			(layer "F.SilkS")
		)
		(fp_line
			(start -0.7874 0.4064)
			(end -0.7874 -0.4064)
			(stroke
				(width 0.1524)
				(type default)
			)
			(layer "F.SilkS")
		)
		(fp_line
			(start 0.7874 -0.4064)
			(end 0.7874 0.4064)
			(stroke
				(width 0.1524)
				(type default)
			)
			(layer "F.SilkS")
		)
		(fp_line
			(start 0.7874 0.4064)
			(end -0.7874 0.4064)
			(stroke
				(width 0.1524)
				(type default)
			)
			(layer "F.SilkS")
		)
		(fp_line
			(start -0.67945 -0.305054)
			(end -0.12065 -0.305054)
			(stroke
				(width 0.1)
				(type default)
			)
			(layer "F.Fab")
		)
		(fp_line
			(start -0.67945 0.3048)
			(end -0.67945 -0.305054)
			(stroke
				(width 0.1)
				(type default)
			)
			(layer "F.Fab")
		)
		(fp_line
			(start -0.12065 -0.305054)
			(end -0.12065 -0.2794)
			(stroke
				(width 0.1)
				(type default)
			)
			(layer "F.Fab")
		)
		(fp_line
			(start -0.12065 -0.2794)
			(end 0.12065 -0.2794)
			(stroke
				(width 0.1)
				(type default)
			)
			(layer "F.Fab")
		)
		(fp_line
			(start -0.12065 0.2794)
			(end -0.12065 0.3048)
			(stroke
				(width 0.1)
				(type default)
			)
			(layer "F.Fab")
		)
		(fp_line
			(start -0.12065 0.3048)
			(end -0.67945 0.3048)
			(stroke
				(width 0.1)
				(type default)
			)
			(layer "F.Fab")
		)
		(fp_line
			(start 0.120396 0.2794)
			(end -0.12065 0.2794)
			(stroke
				(width 0.1)
				(type default)
			)
			(layer "F.Fab")
		)
		(fp_line
			(start 0.120396 0.3048)
			(end 0.120396 0.2794)
			(stroke
				(width 0.1)
				(type default)
			)
			(layer "F.Fab")
		)
		(fp_line
			(start 0.12065 -0.3048)
			(end 0.67945 -0.3048)
			(stroke
				(width 0.1)
				(type default)
			)
			(layer "F.Fab")
		)
		(fp_line
			(start 0.12065 -0.2794)
			(end 0.12065 -0.3048)
			(stroke
				(width 0.1)
				(type default)
			)
			(layer "F.Fab")
		)
		(fp_line
			(start 0.67945 -0.3048)
			(end 0.67945 0.3048)
			(stroke
				(width 0.1)
				(type default)
			)
			(layer "F.Fab")
		)
		(fp_line
			(start 0.67945 0.3048)
			(end 0.120396 0.3048)
			(stroke
				(width 0.1)
				(type default)
			)
			(layer "F.Fab")
		)
		(pad "1" smd circle
			(at -0.40005 0)
			(size 0 0)
			(layers "F.Cu" "F.Mask" "F.Paste")
			(net "P3V3_E1S_0")
		)
		(pad "2" smd circle
			(at 0.40005 0)
			(size 0 0)
			(layers "F.Cu" "F.Mask" "F.Paste")
			(net "RST_SMB_E1S_0_N")
		)
	)
)
